(kicad_pcb
	(version 20260206)
	(generator "pcbnew")
	(generator_version "10.0")
	(general
		(thickness 1.6)
		(legacy_teardrops no)
	)
	(paper "A4")
	(title_block
		(title "03242023_DA0F0TMBIJ0_F0T_Motherboard_J_brd_V01_OCP.brd")
		(comment 1 "Grand Teton / footprints 3384-3388 of 6105")
	)
	(layers
		(0 "F.Cu" signal "TOP")
		(4 "In1.Cu" signal "GND")
		(6 "In2.Cu" signal "IN1")
		(8 "In3.Cu" signal "GND1")
		(10 "In4.Cu" signal "IN2")
		(12 "In5.Cu" signal "GND2")
		(14 "In6.Cu" signal "IN3")
		(16 "In7.Cu" signal "GND3")
		(18 "In8.Cu" signal "VCC")
		(20 "In9.Cu" signal "VCC1")
		(22 "In10.Cu" signal "GND4")
		(24 "In11.Cu" signal "IN4")
		(26 "In12.Cu" signal "GND5")
		(28 "In13.Cu" signal "IN5")
		(30 "In14.Cu" signal "GND6")
		(32 "In15.Cu" signal "IN6")
		(34 "In16.Cu" signal "GND7")
		(2 "B.Cu" signal "BOTTOM")
		(9 "F.Adhes" user "F.Adhesive")
		(11 "B.Adhes" user "B.Adhesive")
		(13 "F.Paste" user "Package Geometry/Pastemask Top")
		(15 "B.Paste" user "Package Geometry/Pastemask Bottom")
		(5 "F.SilkS" user "Ref Des/Silkscreen Top")
		(7 "B.SilkS" user "Ref Des/Silkscreen Bottom")
		(1 "F.Mask" user "Board Geometry/Soldermask Top")
		(3 "B.Mask" user "Board Geometry/Soldermask Bottom")
		(17 "Dwgs.User" user "User.Drawings")
		(19 "Cmts.User" user "User.Comments")
		(21 "Eco1.User" user "User.Eco1")
		(23 "Eco2.User" user "User.Eco2")
		(25 "Edge.Cuts" user "Board Geometry/Outline")
		(27 "Margin" user)
		(31 "F.CrtYd" user "Package Geometry/Place Bound Top")
		(29 "B.CrtYd" user "Package Geometry/Place Bound Bottom")
		(35 "F.Fab" user "Ref Des/Assembly Top")
		(33 "B.Fab" user "Ref Des/Assembly Bottom")
	)
	(footprint ""
		(layer "F.Cu")
		(at 31.540196 -169.04081)
		(property "Reference" "PC394"
			(at 0 0 0)
			(layer "F.SilkS")
			(hide yes)
			(effects
				(font
					(size 1.27 1.27)
				)
			)
		)
		(property "Value" ""
			(at 0 0 0)
			(layer "F.Fab")
			(effects
				(font
					(size 1.27 1.27)
				)
			)
		)
		(duplicate_pad_numbers_are_jumpers no)
		(fp_line
			(start -0.7874 -0.4064)
			(end 0.7874 -0.4064)
			(stroke
				(width 0.1524)
				(type default)
			)
			(layer "F.SilkS")
		)
		(fp_line
			(start -0.7874 0.4064)
			(end -0.7874 -0.4064)
			(stroke
				(width 0.1524)
				(type default)
			)
			(layer "F.SilkS")
		)
		(fp_line
			(start 0.7874 -0.4064)
			(end 0.7874 0.4064)
			(stroke
				(width 0.1524)
				(type default)
			)
			(layer "F.SilkS")
		)
		(fp_line
			(start 0.7874 0.4064)
			(end -0.7874 0.4064)
			(stroke
				(width 0.1524)
				(type default)
			)
			(layer "F.SilkS")
		)
		(fp_line
			(start -0.67945 -0.305054)
			(end -0.12065 -0.305054)
			(stroke
				(width 0.1)
				(type default)
			)
			(layer "F.Fab")
		)
		(fp_line
			(start -0.67945 0.3048)
			(end -0.67945 -0.305054)
			(stroke
				(width 0.1)
				(type default)
			)
			(layer "F.Fab")
		)
		(fp_line
			(start -0.12065 -0.305054)
			(end -0.12065 -0.2794)
			(stroke
				(width 0.1)
				(type default)
			)
			(layer "F.Fab")
		)
		(fp_line
			(start -0.12065 -0.2794)
			(end 0.12065 -0.2794)
			(stroke
				(width 0.1)
				(type default)
			)
			(layer "F.Fab")
		)
		(fp_line
			(start -0.12065 0.2794)
			(end -0.12065 0.3048)
			(stroke
				(width 0.1)
				(type default)
			)
			(layer "F.Fab")
		)
		(fp_line
			(start -0.12065 0.3048)
			(end -0.67945 0.3048)
			(stroke
				(width 0.1)
				(type default)
			)
			(layer "F.Fab")
		)
		(fp_line
			(start 0.120396 0.2794)
			(end -0.12065 0.2794)
			(stroke
				(width 0.1)
				(type default)
			)
			(layer "F.Fab")
		)
		(fp_line
			(start 0.120396 0.3048)
			(end 0.120396 0.2794)
			(stroke
				(width 0.1)
				(type default)
			)
			(layer "F.Fab")
		)
		(fp_line
			(start 0.12065 -0.3048)
			(end 0.67945 -0.3048)
			(stroke
				(width 0.1)
				(type default)
			)
			(layer "F.Fab")
		)
		(fp_line
			(start 0.12065 -0.2794)
			(end 0.12065 -0.3048)
			(stroke
				(width 0.1)
				(type default)
			)
			(layer "F.Fab")
		)
		(fp_line
			(start 0.67945 -0.3048)
			(end 0.67945 0.3048)
			(stroke
				(width 0.1)
				(type default)
			)
			(layer "F.Fab")
		)
		(fp_line
			(start 0.67945 0.3048)
			(end 0.120396 0.3048)
			(stroke
				(width 0.1)
				(type default)
			)
			(layer "F.Fab")
		)
		(pad "1" smd circle
			(at -0.40005 0)
			(size 0 0)
			(layers "F.Cu" "F.Mask" "F.Paste")
			(net "PVCCD_HV_CPU1_VCC")
		)
		(pad "2" smd circle
			(at 0.40005 0)
			(size 0 0)
			(layers "F.Cu" "F.Mask" "F.Paste")
			(net "GND")
		)
	)
	(footprint ""
		(layer "F.Cu")
		(at 317.396622 -52.161948)
		(property "Reference" "R1820"
			(at 0 0 0)
			(layer "F.SilkS")
			(hide yes)
			(effects
				(font
					(size 1.27 1.27)
				)
			)
		)
		(property "Value" ""
			(at 0 0 0)
			(layer "F.Fab")
			(effects
				(font
					(size 1.27 1.27)
				)
			)
		)
		(duplicate_pad_numbers_are_jumpers no)
		(fp_line
			(start -0.7874 -0.4064)
			(end 0.7874 -0.4064)
			(stroke
				(width 0.1524)
				(type default)
			)
			(layer "F.SilkS")
		)
		(fp_line
			(start -0.7874 0.4064)
			(end -0.7874 -0.4064)
			(stroke
				(width 0.1524)
				(type default)
			)
			(layer "F.SilkS")
		)
		(fp_line
			(start 0.7874 -0.4064)
			(end 0.7874 0.4064)
			(stroke
				(width 0.1524)
				(type default)
			)
			(layer "F.SilkS")
		)
		(fp_line
			(start 0.7874 0.4064)
			(end -0.7874 0.4064)
			(stroke
				(width 0.1524)
				(type default)
			)
			(layer "F.SilkS")
		)
		(fp_line
			(start -0.67945 -0.305054)
			(end -0.12065 -0.305054)
			(stroke
				(width 0.1)
				(type default)
			)
			(layer "F.Fab")
		)
		(fp_line
			(start -0.67945 0.3048)
			(end -0.67945 -0.305054)
			(stroke
				(width 0.1)
				(type default)
			)
			(layer "F.Fab")
		)
		(fp_line
			(start -0.12065 -0.305054)
			(end -0.12065 -0.2794)
			(stroke
				(width 0.1)
				(type default)
			)
			(layer "F.Fab")
		)
		(fp_line
			(start -0.12065 -0.2794)
			(end 0.12065 -0.2794)
			(stroke
				(width 0.1)
				(type default)
			)
			(layer "F.Fab")
		)
		(fp_line
			(start -0.12065 0.2794)
			(end -0.12065 0.3048)
			(stroke
				(width 0.1)
				(type default)
			)
			(layer "F.Fab")
		)
		(fp_line
			(start -0.12065 0.3048)
			(end -0.67945 0.3048)
			(stroke
				(width 0.1)
				(type default)
			)
			(layer "F.Fab")
		)
		(fp_line
			(start 0.120396 0.2794)
			(end -0.12065 0.2794)
			(stroke
				(width 0.1)
				(type default)
			)
			(layer "F.Fab")
		)
		(fp_line
			(start 0.120396 0.3048)
			(end 0.120396 0.2794)
			(stroke
				(width 0.1)
				(type default)
			)
			(layer "F.Fab")
		)
		(fp_line
			(start 0.12065 -0.3048)
			(end 0.67945 -0.3048)
			(stroke
				(width 0.1)
				(type default)
			)
			(layer "F.Fab")
		)
		(fp_line
			(start 0.12065 -0.2794)
			(end 0.12065 -0.3048)
			(stroke
				(width 0.1)
				(type default)
			)
			(layer "F.Fab")
		)
		(fp_line
			(start 0.67945 -0.3048)
			(end 0.67945 0.3048)
			(stroke
				(width 0.1)
				(type default)
			)
			(layer "F.Fab")
		)
		(fp_line
			(start 0.67945 0.3048)
			(end 0.120396 0.3048)
			(stroke
				(width 0.1)
				(type default)
			)
			(layer "F.Fab")
		)
		(pad "1" smd circle
			(at -0.40005 0)
			(size 0 0)
			(layers "F.Cu" "F.Mask" "F.Paste")
			(net "P3V3_AUX")
		)
		(pad "2" smd circle
			(at 0.40005 0)
			(size 0 0)
			(layers "F.Cu" "F.Mask" "F.Paste")
			(net "FM_PLT_BMC_THERMTRIP_R_N")
		)
	)
	(footprint ""
		(layer "F.Cu")
		(at 355.8286 -402.9456)
		(property "Reference" "R4733"
			(at 0 0 0)
			(layer "F.SilkS")
			(hide yes)
			(effects
				(font
					(size 1.27 1.27)
				)
			)
		)
		(property "Value" ""
			(at 0 0 0)
			(layer "F.Fab")
			(effects
				(font
					(size 1.27 1.27)
				)
			)
		)
		(duplicate_pad_numbers_are_jumpers no)
		(fp_line
			(start -0.7874 -0.4064)
			(end 0.7874 -0.4064)
			(stroke
				(width 0.1524)
				(type default)
			)
			(layer "F.SilkS")
		)
		(fp_line
			(start -0.7874 0.4064)
			(end -0.7874 -0.4064)
			(stroke
				(width 0.1524)
				(type default)
			)
			(layer "F.SilkS")
		)
		(fp_line
			(start 0.7874 -0.4064)
			(end 0.7874 0.4064)
			(stroke
				(width 0.1524)
				(type default)
			)
			(layer "F.SilkS")
		)
		(fp_line
			(start 0.7874 0.4064)
			(end -0.7874 0.4064)
			(stroke
				(width 0.1524)
				(type default)
			)
			(layer "F.SilkS")
		)
		(fp_line
			(start -0.67945 -0.305054)
			(end -0.12065 -0.305054)
			(stroke
				(width 0.1)
				(type default)
			)
			(layer "F.Fab")
		)
		(fp_line
			(start -0.67945 0.3048)
			(end -0.67945 -0.305054)
			(stroke
				(width 0.1)
				(type default)
			)
			(layer "F.Fab")
		)
		(fp_line
			(start -0.12065 -0.305054)
			(end -0.12065 -0.2794)
			(stroke
				(width 0.1)
				(type default)
			)
			(layer "F.Fab")
		)
		(fp_line
			(start -0.12065 -0.2794)
			(end 0.12065 -0.2794)
			(stroke
				(width 0.1)
				(type default)
			)
			(layer "F.Fab")
		)
		(fp_line
			(start -0.12065 0.2794)
			(end -0.12065 0.3048)
			(stroke
				(width 0.1)
				(type default)
			)
			(layer "F.Fab")
		)
		(fp_line
			(start -0.12065 0.3048)
			(end -0.67945 0.3048)
			(stroke
				(width 0.1)
				(type default)
			)
			(layer "F.Fab")
		)
		(fp_line
			(start 0.120396 0.2794)
			(end -0.12065 0.2794)
			(stroke
				(width 0.1)
				(type default)
			)
			(layer "F.Fab")
		)
		(fp_line
			(start 0.120396 0.3048)
			(end 0.120396 0.2794)
			(stroke
				(width 0.1)
				(type default)
			)
			(layer "F.Fab")
		)
		(fp_line
			(start 0.12065 -0.3048)
			(end 0.67945 -0.3048)
			(stroke
				(width 0.1)
				(type default)
			)
			(layer "F.Fab")
		)
		(fp_line
			(start 0.12065 -0.2794)
			(end 0.12065 -0.3048)
			(stroke
				(width 0.1)
				(type default)
			)
			(layer "F.Fab")
		)
		(fp_line
			(start 0.67945 -0.3048)
			(end 0.67945 0.3048)
			(stroke
				(width 0.1)
				(type default)
			)
			(layer "F.Fab")
		)
		(fp_line
			(start 0.67945 0.3048)
			(end 0.120396 0.3048)
			(stroke
				(width 0.1)
				(type default)
			)
			(layer "F.Fab")
		)
		(pad "1" smd circle
			(at -0.40005 0)
			(size 0 0)
			(layers "F.Cu" "F.Mask" "F.Paste")
			(net "P3V3_AUX")
		)
		(pad "2" smd circle
			(at 0.40005 0)
			(size 0 0)
			(layers "F.Cu" "F.Mask" "F.Paste")
			(net "PRSNT_CABLE_SWB_B2_ISO_N")
		)
	)
	(footprint ""
		(layer "F.Cu")
		(at 432.243992 -402.290534 180)
		(property "Reference" "R3472"
			(at 0 0 180)
			(layer "F.SilkS")
			(hide yes)
			(effects
				(font
					(size 1.27 1.27)
				)
			)
		)
		(property "Value" ""
			(at 0 0 180)
			(layer "F.Fab")
			(effects
				(font
					(size 1.27 1.27)
				)
			)
		)
		(duplicate_pad_numbers_are_jumpers no)
		(fp_line
			(start 0.7874 0.4064)
			(end -0.7874 0.4064)
			(stroke
				(width 0.1524)
				(type default)
			)
			(layer "F.SilkS")
		)
		(fp_line
			(start 0.7874 -0.4064)
			(end 0.7874 0.4064)
			(stroke
				(width 0.1524)
				(type default)
			)
			(layer "F.SilkS")
		)
		(fp_line
			(start -0.7874 0.4064)
			(end -0.7874 -0.4064)
			(stroke
				(width 0.1524)
				(type default)
			)
			(layer "F.SilkS")
		)
		(fp_line
			(start -0.7874 -0.4064)
			(end 0.7874 -0.4064)
			(stroke
				(width 0.1524)
				(type default)
			)
			(layer "F.SilkS")
		)
		(fp_line
			(start 0.67945 0.3048)
			(end 0.120396 0.3048)
			(stroke
				(width 0.1)
				(type default)
			)
			(layer "F.Fab")
		)
		(fp_line
			(start 0.67945 -0.3048)
			(end 0.67945 0.3048)
			(stroke
				(width 0.1)
				(type default)
			)
			(layer "F.Fab")
		)
		(fp_line
			(start 0.12065 -0.2794)
			(end 0.12065 -0.3048)
			(stroke
				(width 0.1)
				(type default)
			)
			(layer "F.Fab")
		)
		(fp_line
			(start 0.12065 -0.3048)
			(end 0.67945 -0.3048)
			(stroke
				(width 0.1)
				(type default)
			)
			(layer "F.Fab")
		)
		(fp_line
			(start 0.120396 0.3048)
			(end 0.120396 0.2794)
			(stroke
				(width 0.1)
				(type default)
			)
			(layer "F.Fab")
		)
		(fp_line
			(start 0.120396 0.2794)
			(end -0.12065 0.2794)
			(stroke
				(width 0.1)
				(type default)
			)
			(layer "F.Fab")
		)
		(fp_line
			(start -0.12065 0.3048)
			(end -0.67945 0.3048)
			(stroke
				(width 0.1)
				(type default)
			)
			(layer "F.Fab")
		)
		(fp_line
			(start -0.12065 0.2794)
			(end -0.12065 0.3048)
			(stroke
				(width 0.1)
				(type default)
			)
			(layer "F.Fab")
		)
		(fp_line
			(start -0.12065 -0.2794)
			(end 0.12065 -0.2794)
			(stroke
				(width 0.1)
				(type default)
			)
			(layer "F.Fab")
		)
		(fp_line
			(start -0.12065 -0.305054)
			(end -0.12065 -0.2794)
			(stroke
				(width 0.1)
				(type default)
			)
			(layer "F.Fab")
		)
		(fp_line
			(start -0.67945 0.3048)
			(end -0.67945 -0.305054)
			(stroke
				(width 0.1)
				(type default)
			)
			(layer "F.Fab")
		)
		(fp_line
			(start -0.67945 -0.305054)
			(end -0.12065 -0.305054)
			(stroke
				(width 0.1)
				(type default)
			)
			(layer "F.Fab")
		)
		(pad "1" smd circle
			(at -0.40005 0 180)
			(size 0 0)
			(layers "F.Cu" "F.Mask" "F.Paste")
			(net "GND")
		)
		(pad "2" smd circle
			(at 0.40005 0 180)
			(size 0 0)
			(layers "F.Cu" "F.Mask" "F.Paste")
			(net "GPU_WP_HW_CTRL_ISO")
		)
	)
	(footprint ""
		(layer "F.Cu")
		(at 420.93388 -156.632148 90)
		(property "Reference" "PR4228"
			(at 0 0 90)
			(layer "F.SilkS")
			(hide yes)
			(effects
				(font
					(size 1.27 1.27)
				)
			)
		)
		(property "Value" ""
			(at 0 0 90)
			(layer "F.Fab")
			(effects
				(font
					(size 1.27 1.27)
				)
			)
		)
		(duplicate_pad_numbers_are_jumpers no)
		(fp_line
			(start 0.7874 -0.4064)
			(end 0.7874 0.4064)
			(stroke
				(width 0.1524)
				(type default)
			)
			(layer "F.SilkS")
		)
		(fp_line
			(start -0.7874 -0.4064)
			(end 0.7874 -0.4064)
			(stroke
				(width 0.1524)
				(type default)
			)
			(layer "F.SilkS")
		)
		(fp_line
			(start 0.7874 0.4064)
			(end -0.7874 0.4064)
			(stroke
				(width 0.1524)
				(type default)
			)
			(layer "F.SilkS")
		)
		(fp_line
			(start -0.7874 0.4064)
			(end -0.7874 -0.4064)
			(stroke
				(width 0.1524)
				(type default)
			)
			(layer "F.SilkS")
		)
		(fp_line
			(start -0.12065 -0.305054)
			(end -0.12065 -0.2794)
			(stroke
				(width 0.1)
				(type default)
			)
			(layer "F.Fab")
		)
		(fp_line
			(start -0.67945 -0.305054)
			(end -0.12065 -0.305054)
			(stroke
				(width 0.1)
				(type default)
			)
			(layer "F.Fab")
		)
		(fp_line
			(start 0.67945 -0.3048)
			(end 0.67945 0.3048)
			(stroke
				(width 0.1)
				(type default)
			)
			(layer "F.Fab")
		)
		(fp_line
			(start 0.12065 -0.3048)
			(end 0.67945 -0.3048)
			(stroke
				(width 0.1)
				(type default)
			)
			(layer "F.Fab")
		)
		(fp_line
			(start 0.12065 -0.2794)
			(end 0.12065 -0.3048)
			(stroke
				(width 0.1)
				(type default)
			)
			(layer "F.Fab")
		)
		(fp_line
			(start -0.12065 -0.2794)
			(end 0.12065 -0.2794)
			(stroke
				(width 0.1)
				(type default)
			)
			(layer "F.Fab")
		)
		(fp_line
			(start 0.120396 0.2794)
			(end -0.12065 0.2794)
			(stroke
				(width 0.1)
				(type default)
			)
			(layer "F.Fab")
		)
		(fp_line
			(start -0.12065 0.2794)
			(end -0.12065 0.3048)
			(stroke
				(width 0.1)
				(type default)
			)
			(layer "F.Fab")
		)
		(fp_line
			(start 0.67945 0.3048)
			(end 0.120396 0.3048)
			(stroke
				(width 0.1)
				(type default)
			)
			(layer "F.Fab")
		)
		(fp_line
			(start 0.120396 0.3048)
			(end 0.120396 0.2794)
			(stroke
				(width 0.1)
				(type default)
			)
			(layer "F.Fab")
		)
		(fp_line
			(start -0.12065 0.3048)
			(end -0.67945 0.3048)
			(stroke
				(width 0.1)
				(type default)
			)
			(layer "F.Fab")
		)
		(fp_line
			(start -0.67945 0.3048)
			(end -0.67945 -0.305054)
			(stroke
				(width 0.1)
				(type default)
			)
			(layer "F.Fab")
		)
		(pad "1" smd circle
			(at -0.40005 0 90)
			(size 0 0)
			(layers "F.Cu" "F.Mask" "F.Paste")
			(net "PVCCFA_EHV_CPU0_FAULT")
		)
		(pad "2" smd circle
			(at 0.40005 0 90)
			(size 0 0)
			(layers "F.Cu" "F.Mask" "F.Paste")
			(net "GND")
		)
	)
)
